(kicad_pcb
	(version 20260206)
	(generator "pcbnew")
	(generator_version "10.0")
	(general
		(thickness 1.21888)
		(legacy_teardrops no)
	)
	(paper "A4")
	(title_block
		(title "timecard-proto-v0 — Timingcard_PCB.PcbDoc")
		(comment 1 "Time Appliance Project (Time Card) / footprints 101-111 of 167")
	)
	(layers
		(0 "F.Cu" signal "TOP")
		(4 "In1.Cu" signal "SGND")
		(6 "In2.Cu" signal "IN1")
		(8 "In3.Cu" signal "IN2")
		(10 "In4.Cu" signal "SGND1")
		(2 "B.Cu" signal "BOTTOM")
		(9 "F.Adhes" user "F.Adhesive")
		(11 "B.Adhes" user "B.Adhesive")
		(13 "F.Paste" user "Top Paste")
		(15 "B.Paste" user "Bottom Paste")
		(5 "F.SilkS" user "Top Overlay")
		(7 "B.SilkS" user "Bottom Overlay")
		(1 "F.Mask" user "Top Solder")
		(3 "B.Mask" user "Bottom Solder")
		(17 "Dwgs.User" user "User.Drawings")
		(19 "Cmts.User" user "User.Comments")
		(21 "Eco1.User" user "User.Eco1")
		(23 "Eco2.User" user "User.Eco2")
		(25 "Edge.Cuts" user)
		(27 "Margin" user)
		(31 "F.CrtYd" user "Top Courtyard")
		(29 "B.CrtYd" user "Bottom Courtyard")
		(35 "F.Fab" user "Top Component Center")
		(33 "B.Fab" user "Bottom Component Center")
	)
	(footprint "Miscellaneous Devices:J1-0603"
		(layer "F.Cu")
		(at 113.138595 57.8286 -90)
		(property "Reference" "R12"
			(at 0.2786 -6.123079 270)
			(unlocked yes)
			(layer "F.SilkS")
			(effects
				(font
					(size 0.762 0.762)
					(thickness 0.2286)
				)
			)
		)
		(property "Value" "GPS2RX"
			(at 4.335402 -4.227705 0)
			(unlocked yes)
			(layer "F.SilkS")
			(hide yes)
			(effects
				(font
					(size 1.524 1.524)
					(thickness 0.254)
				)
			)
		)
		(sheetname "GPS_IMU_SENSORS")
		(sheetfile "GPS_IMU_SENSORS.kicad_sch")
		(duplicate_pad_numbers_are_jumpers no)
		(fp_line
			(start 0.2 0.35)
			(end -0.2 0.35)
			(stroke
				(width 0.2)
				(type solid)
			)
			(layer "F.SilkS")
		)
		(fp_line
			(start 0.2 -0.35)
			(end -0.2 -0.35)
			(stroke
				(width 0.2)
				(type solid)
			)
			(layer "F.SilkS")
		)
		(pad "1" smd rect
			(at -0.75 0)
			(size 0.9 0.7)
			(layers "F.Cu" "F.Mask" "F.Paste")
			(net "GPS2_RX")
		)
		(pad "2" smd rect
			(at 0.75 0)
			(size 0.9 0.7)
			(layers "F.Cu" "F.Mask" "F.Paste")
			(net "NetJP2_3")
		)
	)
	(footprint "Vault:CAPC1608X87X45ML20T05"
		(layer "F.Cu")
		(at 167.069595 82.8276 -90)
		(property "Reference" "C80"
			(at -3.799 -2.362345 90)
			(unlocked yes)
			(layer "F.SilkS")
			(effects
				(font
					(size 0.762 0.762)
					(thickness 0.2286)
				)
				(justify left bottom)
			)
		)
		(property "Value" "0.1uF"
			(at 3.47599 0.2921 0)
			(unlocked yes)
			(layer "F.SilkS")
			(hide yes)
			(effects
				(font
					(size 1.524 1.524)
					(thickness 0.254)
				)
				(justify left bottom)
			)
		)
		(sheetname "MAC")
		(sheetfile "MAC.kicad_sch")
		(duplicate_pad_numbers_are_jumpers no)
		(pad "1" smd rect
			(at -0.7 0)
			(size 1.1 1.05)
			(layers "F.Cu" "F.Mask" "F.Paste")
			(net "GND")
		)
		(pad "2" smd rect
			(at 0.7 0)
			(size 1.1 1.05)
			(layers "F.Cu" "F.Mask" "F.Paste")
			(net "+3.3V_CLEAN")
		)
	)
	(footprint "Connectors:SAMTEC_HTST-105-01-L-DV-A"
		(layer "F.Cu")
		(at 138.367595 56.7916)
		(property "Reference" "U5"
			(at -13.09339 -3.347545 0)
			(unlocked yes)
			(layer "F.SilkS")
			(effects
				(font
					(size 0.762 0.762)
					(thickness 0.2286)
				)
				(justify left bottom)
			)
		)
		(property "Value" "HTST-105-01-L-DV-A"
			(at -4.3317 21.99359 0)
			(unlocked yes)
			(layer "F.SilkS")
			(hide yes)
			(effects
				(font
					(size 1.524 1.524)
					(thickness 0.254)
				)
				(justify left bottom)
			)
		)
		(sheetname "PCIe_JTAG")
		(sheetfile "PCIe_JTAG.kicad_sch")
		(duplicate_pad_numbers_are_jumpers no)
		(fp_line
			(start -10.16 -4.635)
			(end -6.065 -4.635)
			(stroke
				(width 0.2)
				(type solid)
			)
			(layer "F.SilkS")
		)
		(fp_line
			(start -10.16 4.635)
			(end -10.16 -4.635)
			(stroke
				(width 0.2)
				(type solid)
			)
			(layer "F.SilkS")
		)
		(fp_line
			(start -10.16 4.635)
			(end -6.065 4.635)
			(stroke
				(width 0.2)
				(type solid)
			)
			(layer "F.SilkS")
		)
		(fp_line
			(start 6.065 -4.635)
			(end 10.16 -4.635)
			(stroke
				(width 0.2)
				(type solid)
			)
			(layer "F.SilkS")
		)
		(fp_line
			(start 6.065 4.635)
			(end 10.16 4.635)
			(stroke
				(width 0.2)
				(type solid)
			)
			(layer "F.SilkS")
		)
		(fp_line
			(start 10.16 4.635)
			(end 10.16 -4.635)
			(stroke
				(width 0.2)
				(type solid)
			)
			(layer "F.SilkS")
		)
		(fp_circle
			(center -7.62 5.715)
			(end -7.62 5.08)
			(stroke
				(width 0.2)
				(type solid)
			)
			(fill no)
			(layer "F.SilkS")
		)
		(pad "" np_thru_hole circle
			(at -3.81 0)
			(size 1.676 1.676)
			(drill 1.676)
			(layers "*.Cu" "*.Mask")
			(thermal_bridge_angle 90)
		)
		(pad "" np_thru_hole circle
			(at 3.81 0)
			(size 1.676 1.676)
			(drill 1.676)
			(layers "*.Cu" "*.Mask")
			(thermal_bridge_angle 90)
		)
		(pad "1" smd rect
			(at -5.08 3.43)
			(size 1.27 5.08)
			(layers "F.Cu" "F.Mask" "F.Paste")
			(net "NetR18_2")
		)
		(pad "2" smd rect
			(at -5.08 -3.43)
			(size 1.27 5.08)
			(layers "F.Cu" "F.Mask" "F.Paste")
			(net "GND")
		)
		(pad "3" smd rect
			(at -2.54 3.43)
			(size 1.27 5.08)
			(layers "F.Cu" "F.Mask" "F.Paste")
			(net "NetR19_2")
		)
		(pad "4" smd rect
			(at -2.54 -3.43)
			(size 1.27 5.08)
			(layers "F.Cu" "F.Mask" "F.Paste")
			(net "+3.3V")
		)
		(pad "5" smd rect
			(at 0 3.43)
			(size 1.27 5.08)
			(layers "F.Cu" "F.Mask" "F.Paste")
			(net "NetR20_2")
		)
		(pad "6" smd rect
			(at 0 -3.43)
			(size 1.27 5.08)
			(layers "F.Cu" "F.Mask" "F.Paste")
			(net "+3.3V")
		)
		(pad "7" smd rect
			(at 2.54 3.43)
			(size 1.27 5.08)
			(layers "F.Cu" "F.Mask" "F.Paste")
		)
		(pad "8" smd rect
			(at 2.54 -3.43)
			(size 1.27 5.08)
			(layers "F.Cu" "F.Mask" "F.Paste")
		)
		(pad "9" smd rect
			(at 5.08 3.43)
			(size 1.27 5.08)
			(layers "F.Cu" "F.Mask" "F.Paste")
			(net "NetR21_2")
		)
		(pad "10" smd rect
			(at 5.08 -3.43)
			(size 1.27 5.08)
			(layers "F.Cu" "F.Mask" "F.Paste")
			(net "GND")
		)
	)
	(footprint "Capacitors:CAPC1608X10N"
		(layer "F.Cu")
		(at 165.037595 63.9046 -90)
		(property "Reference" "C55"
			(at -2.926 -0.844345 90)
			(unlocked yes)
			(layer "F.SilkS")
			(effects
				(font
					(size 0.762 0.762)
					(thickness 0.2286)
				)
				(justify left bottom)
			)
		)
		(property "Value" "GRT188R61E106ME13D"
			(at 4.08559 0.5461 0)
			(unlocked yes)
			(layer "F.SilkS")
			(hide yes)
			(effects
				(font
					(size 1.524 1.524)
					(thickness 0.254)
				)
				(justify left bottom)
			)
		)
		(sheetname "UART")
		(sheetfile "UART.kicad_sch")
		(duplicate_pad_numbers_are_jumpers no)
		(fp_line
			(start 0.635 0.7112)
			(end -0.635 0.7112)
			(stroke
				(width 0.1524)
				(type solid)
			)
			(layer "F.SilkS")
		)
		(fp_line
			(start 0.635 -0.7112)
			(end -0.635 -0.7112)
			(stroke
				(width 0.1524)
				(type solid)
			)
			(layer "F.SilkS")
		)
		(pad "1" smd rect
			(at -0.8 0)
			(size 0.95 1)
			(layers "F.Cu" "F.Mask" "F.Paste")
			(net "GND")
		)
		(pad "2" smd rect
			(at 0.8 0)
			(size 0.95 1)
			(layers "F.Cu" "F.Mask" "F.Paste")
			(net "NetC54_2")
		)
	)
	(footprint "Capacitors:CAPC2012X14N"
		(layer "F.Cu")
		(at 227.775595 121.6896 180)
		(property "Reference" "C14"
			(at -1.97531 -1.604455 0)
			(unlocked yes)
			(layer "F.SilkS")
			(effects
				(font
					(size 0.762 0.762)
					(thickness 0.2286)
				)
				(justify left bottom)
			)
		)
		(property "Value" "CAP_0805_10UF_25V"
			(at 4.6355 -3.78079 0)
			(unlocked yes)
			(layer "F.SilkS")
			(hide yes)
			(effects
				(font
					(size 1.524 1.524)
					(thickness 0.254)
				)
				(justify left bottom)
			)
		)
		(sheetname "POWER")
		(sheetfile "POWER.kicad_sch")
		(duplicate_pad_numbers_are_jumpers no)
		(fp_line
			(start 0.762 0.9652)
			(end -0.762 0.9652)
			(stroke
				(width 0.1524)
				(type solid)
			)
			(layer "F.SilkS")
		)
		(fp_line
			(start 0.762 -0.9652)
			(end -0.762 -0.9652)
			(stroke
				(width 0.1524)
				(type solid)
			)
			(layer "F.SilkS")
		)
		(pad "1" smd rect
			(at -0.9 0 270)
			(size 1.45 1.15)
			(layers "F.Cu" "F.Mask" "F.Paste")
			(net "+5.0V")
		)
		(pad "2" smd rect
			(at 0.9 0 270)
			(size 1.45 1.15)
			(layers "F.Cu" "F.Mask" "F.Paste")
			(net "GND")
		)
	)
	(footprint "Capacitors:CAPC1608X10N"
		(layer "F.Cu")
		(at 224.092595 110.1326 -90)
		(property "Reference" "C4"
			(at -2.029 -0.364345 90)
			(unlocked yes)
			(layer "F.SilkS")
			(effects
				(font
					(size 0.762 0.762)
					(thickness 0.2286)
				)
				(justify left bottom)
			)
		)
		(property "Value" "CAP_0603_0.01UF_50V"
			(at 3.14579 4.7879 0)
			(unlocked yes)
			(layer "F.SilkS")
			(hide yes)
			(effects
				(font
					(size 1.524 1.524)
					(thickness 0.254)
				)
				(justify left bottom)
			)
		)
		(sheetname "POWER")
		(sheetfile "POWER.kicad_sch")
		(duplicate_pad_numbers_are_jumpers no)
		(fp_line
			(start 0.635 0.7112)
			(end -0.635 0.7112)
			(stroke
				(width 0.1524)
				(type solid)
			)
			(layer "F.SilkS")
		)
		(fp_line
			(start 0.635 -0.7112)
			(end -0.635 -0.7112)
			(stroke
				(width 0.1524)
				(type solid)
			)
			(layer "F.SilkS")
		)
		(pad "1" smd rect
			(at -0.8 0)
			(size 0.95 1)
			(layers "F.Cu" "F.Mask" "F.Paste")
			(net "NetC4_1")
		)
		(pad "2" smd rect
			(at 0.8 0)
			(size 0.95 1)
			(layers "F.Cu" "F.Mask" "F.Paste")
			(net "NetC4_2")
		)
	)
	(footprint "Resistors:RESC1608X50N"
		(layer "F.Cu")
		(at 216.853595 105.8146 -90)
		(property "Reference" "R3"
			(at 2.864 -0.428345 90)
			(unlocked yes)
			(layer "F.SilkS")
			(effects
				(font
					(size 0.762 0.762)
					(thickness 0.2286)
				)
				(justify left bottom)
			)
		)
		(property "Value" "ERJ-3EKF4702V"
			(at -18.92681 -16.2687 0)
			(unlocked yes)
			(layer "F.SilkS")
			(hide yes)
			(effects
				(font
					(size 1.524 1.524)
					(thickness 0.254)
				)
				(justify left bottom)
			)
		)
		(sheetname "POWER")
		(sheetfile "POWER.kicad_sch")
		(duplicate_pad_numbers_are_jumpers no)
		(fp_line
			(start 0 0.5)
			(end 0 -0.5)
			(stroke
				(width 0.1524)
				(type solid)
			)
			(layer "F.SilkS")
		)
		(pad "1" smd rect
			(at -0.69 0)
			(size 1 0.72)
			(layers "F.Cu" "F.Mask" "F.Paste")
			(net "NetR3_1")
		)
		(pad "2" smd rect
			(at 0.69 0)
			(size 1 0.72)
			(layers "F.Cu" "F.Mask" "F.Paste")
			(net "+12V")
		)
	)
	(footprint "Vault:TECO-1909763-1_V"
		(layer "F.Cu")
		(at 75.088595 137.5786 90)
		(property "Reference" "J10"
			(at -3.026921 2.4286 0)
			(unlocked yes)
			(layer "F.SilkS")
			(effects
				(font
					(size 0.762 0.762)
					(thickness 0.2286)
				)
			)
		)
		(property "Value" "1909763-1"
			(at 4.608085 3.749802 90)
			(unlocked yes)
			(layer "F.SilkS")
			(hide yes)
			(effects
				(font
					(size 1.524 1.524)
					(thickness 0.254)
				)
			)
		)
		(sheetname "USER_IO")
		(sheetfile "USER_IO.kicad_sch")
		(duplicate_pad_numbers_are_jumpers no)
		(fp_line
			(start -0.55 -1.3)
			(end 0.55 -1.3)
			(stroke
				(width 0.2)
				(type solid)
			)
			(layer "F.SilkS")
		)
		(fp_circle
			(center -1.778 1.65)
			(end -1.653 1.65)
			(stroke
				(width 0.25)
				(type solid)
			)
			(fill no)
			(layer "F.SilkS")
		)
		(pad "1" smd rect
			(at -1.475 0 90)
			(size 1.05 2.2)
			(layers "F.Cu" "F.Mask" "F.Paste")
			(net "GND")
		)
		(pad "2" smd rect
			(at 0 1.525 90)
			(size 1 1.05)
			(layers "F.Cu" "F.Mask" "F.Paste")
			(net "ANT4")
		)
		(pad "3" smd rect
			(at 1.475 0 90)
			(size 1.05 2.2)
			(layers "F.Cu" "F.Mask" "F.Paste")
			(net "GND")
		)
	)
	(footprint "Modules:LGA-28"
		(layer "F.Cu")
		(at 222.314595 78.2556 -90)
		(property "Reference" "U8"
			(at -3.564255 2.0574 0)
			(unlocked yes)
			(layer "F.SilkS")
			(effects
				(font
					(size 0.762 0.762)
					(thickness 0.2286)
				)
				(justify left bottom)
			)
		)
		(property "Value" "BNO080"
			(at 5.76199 -16.1163 0)
			(unlocked yes)
			(layer "F.SilkS")
			(hide yes)
			(effects
				(font
					(size 1.524 1.524)
					(thickness 0.254)
				)
				(justify left bottom)
			)
		)
		(sheetname "GPS_IMU_SENSORS")
		(sheetfile "GPS_IMU_SENSORS.kicad_sch")
		(duplicate_pad_numbers_are_jumpers no)
		(fp_line
			(start -2.794 2.159)
			(end -2.794 -2.154)
			(stroke
				(width 0.254)
				(type solid)
			)
			(layer "F.SilkS")
		)
		(fp_line
			(start 2.794 2.159)
			(end -2.794 2.159)
			(stroke
				(width 0.254)
				(type solid)
			)
			(layer "F.SilkS")
		)
		(fp_line
			(start 2.794 2.159)
			(end 2.794 -2.154)
			(stroke
				(width 0.254)
				(type solid)
			)
			(layer "F.SilkS")
		)
		(fp_line
			(start 2.794 -2.154)
			(end -2.794 -2.154)
			(stroke
				(width 0.254)
				(type solid)
			)
			(layer "F.SilkS")
		)
		(fp_rect
			(start 2.159 -2.413)
			(end 2.413 -3.048)
			(stroke
				(width 0)
				(type default)
			)
			(fill yes)
			(layer "F.SilkS")
		)
		(pad "1" smd rect
			(at 2.25 -1.5625 90)
			(size 0.25 0.675)
			(layers "F.Cu" "F.Mask" "F.Paste")
		)
		(pad "2" smd rect
			(at 2.3125 -0.75 270)
			(size 0.575 0.25)
			(layers "F.Cu" "F.Mask" "F.Paste")
			(net "GND")
		)
		(pad "3" smd rect
			(at 2.3125 -0.254 270)
			(size 0.575 0.25)
			(layers "F.Cu" "F.Mask" "F.Paste")
			(net "+3.3V")
		)
		(pad "4" smd rect
			(at 2.3125 0.25 270)
			(size 0.575 0.25)
			(layers "F.Cu" "F.Mask" "F.Paste")
			(net "IMU_BOOT")
		)
		(pad "5" smd rect
			(at 2.3125 0.75 270)
			(size 0.575 0.25)
			(layers "F.Cu" "F.Mask" "F.Paste")
			(net "IMU_PS1")
		)
		(pad "6" smd rect
			(at 2.25 1.5625 90)
			(size 0.25 0.675)
			(layers "F.Cu" "F.Mask" "F.Paste")
			(net "IMU_PS0")
		)
		(pad "7" smd rect
			(at 1.75 1.5625 90)
			(size 0.25 0.675)
			(layers "F.Cu" "F.Mask" "F.Paste")
		)
		(pad "8" smd rect
			(at 1.25 1.5625 90)
			(size 0.25 0.675)
			(layers "F.Cu" "F.Mask" "F.Paste")
		)
		(pad "9" smd rect
			(at 0.75 1.5625 90)
			(size 0.25 0.675)
			(layers "F.Cu" "F.Mask" "F.Paste")
		)
		(pad "10" smd rect
			(at 0.25 1.5625 90)
			(size 0.25 0.675)
			(layers "F.Cu" "F.Mask" "F.Paste")
			(net "IMU_CLKSEL0")
		)
		(pad "11" smd rect
			(at -0.25 1.5625 90)
			(size 0.25 0.675)
			(layers "F.Cu" "F.Mask" "F.Paste")
			(net "IMU_NRST")
		)
		(pad "12" smd rect
			(at -0.75 1.5625 90)
			(size 0.25 0.675)
			(layers "F.Cu" "F.Mask" "F.Paste")
		)
		(pad "13" smd rect
			(at -1.25 1.5625 90)
			(size 0.25 0.675)
			(layers "F.Cu" "F.Mask" "F.Paste")
		)
		(pad "14" smd rect
			(at -1.75 1.5625 90)
			(size 0.25 0.675)
			(layers "F.Cu" "F.Mask" "F.Paste")
			(net "IMU_INT")
		)
		(pad "15" smd rect
			(at -2.25 1.5625 90)
			(size 0.25 0.675)
			(layers "F.Cu" "F.Mask" "F.Paste")
			(net "IMU_ENV_SCL")
		)
		(pad "16" smd rect
			(at -2.3125 0.75 90)
			(size 0.575 0.25)
			(layers "F.Cu" "F.Mask" "F.Paste")
			(net "IMU_ENV_SDA")
		)
		(pad "17" smd rect
			(at -2.3125 0.25 90)
			(size 0.575 0.25)
			(layers "F.Cu" "F.Mask" "F.Paste")
			(net "MOSI")
		)
		(pad "18" smd rect
			(at -2.3125 -0.25 90)
			(size 0.575 0.25)
			(layers "F.Cu" "F.Mask" "F.Paste")
			(net "CSN")
		)
		(pad "19" smd rect
			(at -2.3125 -0.75 90)
			(size 0.575 0.25)
			(layers "F.Cu" "F.Mask" "F.Paste")
			(net "SCK")
		)
		(pad "20" smd rect
			(at -2.25 -1.5625 90)
			(size 0.25 0.675)
			(layers "F.Cu" "F.Mask" "F.Paste")
			(net "MISO")
		)
		(pad "21" smd rect
			(at -1.75 -1.5625 90)
			(size 0.25 0.675)
			(layers "F.Cu" "F.Mask" "F.Paste")
		)
		(pad "22" smd rect
			(at -1.25 -1.5625 90)
			(size 0.25 0.675)
			(layers "F.Cu" "F.Mask" "F.Paste")
		)
		(pad "23" smd rect
			(at -0.75 -1.5625 90)
			(size 0.25 0.675)
			(layers "F.Cu" "F.Mask" "F.Paste")
		)
		(pad "24" smd rect
			(at -0.25 -1.5625 90)
			(size 0.25 0.675)
			(layers "F.Cu" "F.Mask" "F.Paste")
		)
		(pad "25" smd rect
			(at 0.25 -1.5625 90)
			(size 0.25 0.675)
			(layers "F.Cu" "F.Mask" "F.Paste")
			(net "GND")
		)
		(pad "26" smd rect
			(at 0.75 -1.5625 90)
			(size 0.25 0.675)
			(layers "F.Cu" "F.Mask" "F.Paste")
			(net "NetC86_2")
		)
		(pad "27" smd rect
			(at 1.25 -1.5625 90)
			(size 0.25 0.675)
			(layers "F.Cu" "F.Mask" "F.Paste")
			(net "NetC85_2")
		)
		(pad "28" smd rect
			(at 1.75 -1.5625 90)
			(size 0.25 0.675)
			(layers "F.Cu" "F.Mask" "F.Paste")
			(net "+3.3V")
		)
	)
	(footprint "Passives:DIOM6959X26N"
		(layer "F.Cu")
		(at 85.027595 110.8946 180)
		(property "Reference" "D15"
			(at 4.1402 4.097655 0)
			(unlocked yes)
			(layer "F.SilkS")
			(effects
				(font
					(size 0.762 0.762)
					(thickness 0.2286)
				)
				(justify left bottom)
			)
		)
		(property "Value" "SMCJ6.5CA"
			(at 4.2545 -5.91439 0)
			(unlocked yes)
			(layer "F.SilkS")
			(hide yes)
			(effects
				(font
					(size 1.524 1.524)
					(thickness 0.254)
				)
				(justify left bottom)
			)
		)
		(sheetname "USER_IO")
		(sheetfile "USER_IO.kicad_sch")
		(duplicate_pad_numbers_are_jumpers no)
		(fp_line
			(start 3.6 3.15)
			(end -3.6 3.15)
			(stroke
				(width 0.2)
				(type solid)
			)
			(layer "F.SilkS")
		)
		(fp_line
			(start 3.6 1.975)
			(end 3.6 3.15)
			(stroke
				(width 0.2)
				(type solid)
			)
			(layer "F.SilkS")
		)
		(fp_line
			(start 3.6 -3.15)
			(end 3.6 -1.975)
			(stroke
				(width 0.2)
				(type solid)
			)
			(layer "F.SilkS")
		)
		(fp_line
			(start 3.6 -3.15)
			(end -3.6 -3.15)
			(stroke
				(width 0.2)
				(type solid)
			)
			(layer "F.SilkS")
		)
		(fp_line
			(start -3.6 1.975)
			(end -3.6 3.15)
			(stroke
				(width 0.2)
				(type solid)
			)
			(layer "F.SilkS")
		)
		(fp_line
			(start -3.6 -3.15)
			(end -3.6 -1.975)
			(stroke
				(width 0.2)
				(type solid)
			)
			(layer "F.SilkS")
		)
		(fp_circle
			(center -4.25 -2.125)
			(end -4.25 -2)
			(stroke
				(width 0.25)
				(type solid)
			)
			(fill no)
			(layer "F.SilkS")
		)
		(pad "A" smd rect
			(at 2.85 0 270)
			(size 3.15 2.45)
			(layers "F.Cu" "F.Mask" "F.Paste")
			(net "ANT2")
		)
		(pad "K" smd rect
			(at -2.85 0 270)
			(size 3.15 2.45)
			(layers "F.Cu" "F.Mask" "F.Paste")
			(net "GND")
		)
	)
	(footprint "Capacitors:CAPC1608X10N"
		(layer "F.Cu")
		(at 161.100595 82.8276 -90)
		(property "Reference" "C76"
			(at -3.249 1.368655 90)
			(unlocked yes)
			(layer "F.SilkS")
			(effects
				(font
					(size 0.762 0.762)
					(thickness 0.2286)
				)
				(justify left bottom)
			)
		)
		(property "Value" "CAP_0603_0.01UF_50V"
			(at 4.08559 0.5461 0)
			(unlocked yes)
			(layer "F.SilkS")
			(hide yes)
			(effects
				(font
					(size 1.524 1.524)
					(thickness 0.254)
				)
				(justify left bottom)
			)
		)
		(sheetname "MAC")
		(sheetfile "MAC.kicad_sch")
		(duplicate_pad_numbers_are_jumpers no)
		(fp_line
			(start 0.635 0.7112)
			(end -0.635 0.7112)
			(stroke
				(width 0.1524)
				(type solid)
			)
			(layer "F.SilkS")
		)
		(fp_line
			(start 0.635 -0.7112)
			(end -0.635 -0.7112)
			(stroke
				(width 0.1524)
				(type solid)
			)
			(layer "F.SilkS")
		)
		(pad "1" smd rect
			(at -0.8 0)
			(size 0.95 1)
			(layers "F.Cu" "F.Mask" "F.Paste")
			(net "GND")
		)
		(pad "2" smd rect
			(at 0.8 0)
			(size 0.95 1)
			(layers "F.Cu" "F.Mask" "F.Paste")
			(net "+3.3V_CLEAN")
		)
	)
)
